(kicad_pcb
	(version 20260206)
	(generator "pcbnew")
	(generator_version "10.0")
	(general
		(thickness 1.6)
		(legacy_teardrops no)
	)
	(paper "A4")
	(title_block
		(title "04192023_DAF0TMB3IC0_F0TG_MB_C_brd_V02_OCP.brd")
		(comment 1 "Grand Teton / footprints 5210-5216 of 8354")
	)
	(layers
		(0 "F.Cu" signal "TOP")
		(4 "In1.Cu" signal "GND")
		(6 "In2.Cu" signal "IN1")
		(8 "In3.Cu" signal "GND1")
		(10 "In4.Cu" signal "IN2")
		(12 "In5.Cu" signal "GND2")
		(14 "In6.Cu" signal "IN3")
		(16 "In7.Cu" signal "GND3")
		(18 "In8.Cu" signal "VCC")
		(20 "In9.Cu" signal "VCC1")
		(22 "In10.Cu" signal "GND4")
		(24 "In11.Cu" signal "IN4")
		(26 "In12.Cu" signal "GND5")
		(28 "In13.Cu" signal "IN5")
		(30 "In14.Cu" signal "GND6")
		(32 "In15.Cu" signal "IN6")
		(34 "In16.Cu" signal "GND7")
		(2 "B.Cu" signal "BOTTOM")
		(9 "F.Adhes" user "F.Adhesive")
		(11 "B.Adhes" user "B.Adhesive")
		(13 "F.Paste" user "Package Geometry/Pastemask Top")
		(15 "B.Paste" user "Package Geometry/Pastemask Bottom")
		(5 "F.SilkS" user "Ref Des/Silkscreen Top")
		(7 "B.SilkS" user "Ref Des/Silkscreen Bottom")
		(1 "F.Mask" user "Board Geometry/Soldermask Top")
		(3 "B.Mask" user "Board Geometry/Soldermask Bottom")
		(17 "Dwgs.User" user "User.Drawings")
		(19 "Cmts.User" user "User.Comments")
		(21 "Eco1.User" user "User.Eco1")
		(23 "Eco2.User" user "User.Eco2")
		(25 "Edge.Cuts" user "Board Geometry/Outline")
		(27 "Margin" user)
		(31 "F.CrtYd" user "Package Geometry/Place Bound Top")
		(29 "B.CrtYd" user "Package Geometry/Place Bound Bottom")
		(35 "F.Fab" user "Ref Des/Assembly Top")
		(33 "B.Fab" user "Ref Des/Assembly Bottom")
	)
	(footprint ""
		(layer "B.Cu")
		(at 281.391614 -347.77553 -90)
		(property "Reference" "PR108"
			(at 0 0 90)
			(layer "B.SilkS")
			(hide yes)
			(effects
				(font
					(size 1.27 1.27)
				)
				(justify mirror)
			)
		)
		(property "Value" ""
			(at 0 0 90)
			(layer "B.Fab")
			(effects
				(font
					(size 1.27 1.27)
				)
				(justify mirror)
			)
		)
		(duplicate_pad_numbers_are_jumpers no)
		(fp_line
			(start -0.7874 0.4064)
			(end 0.7874 0.4064)
			(stroke
				(width 0.1524)
				(type default)
			)
			(layer "B.SilkS")
		)
		(fp_line
			(start 0.7874 0.4064)
			(end 0.7874 -0.4064)
			(stroke
				(width 0.1524)
				(type default)
			)
			(layer "B.SilkS")
		)
		(fp_line
			(start -0.7874 -0.4064)
			(end -0.7874 0.4064)
			(stroke
				(width 0.1524)
				(type default)
			)
			(layer "B.SilkS")
		)
		(fp_line
			(start 0.7874 -0.4064)
			(end -0.7874 -0.4064)
			(stroke
				(width 0.1524)
				(type default)
			)
			(layer "B.SilkS")
		)
		(fp_line
			(start -0.67945 0.3048)
			(end -0.120396 0.3048)
			(stroke
				(width 0.1)
				(type default)
			)
			(layer "B.Fab")
		)
		(fp_line
			(start -0.120396 0.3048)
			(end -0.120396 0.2794)
			(stroke
				(width 0.1)
				(type default)
			)
			(layer "B.Fab")
		)
		(fp_line
			(start 0.12065 0.3048)
			(end 0.67945 0.3048)
			(stroke
				(width 0.1)
				(type default)
			)
			(layer "B.Fab")
		)
		(fp_line
			(start 0.67945 0.3048)
			(end 0.67945 -0.305054)
			(stroke
				(width 0.1)
				(type default)
			)
			(layer "B.Fab")
		)
		(fp_line
			(start -0.120396 0.2794)
			(end 0.12065 0.2794)
			(stroke
				(width 0.1)
				(type default)
			)
			(layer "B.Fab")
		)
		(fp_line
			(start 0.12065 0.2794)
			(end 0.12065 0.3048)
			(stroke
				(width 0.1)
				(type default)
			)
			(layer "B.Fab")
		)
		(fp_line
			(start -0.12065 -0.2794)
			(end -0.12065 -0.3048)
			(stroke
				(width 0.1)
				(type default)
			)
			(layer "B.Fab")
		)
		(fp_line
			(start 0.12065 -0.2794)
			(end -0.12065 -0.2794)
			(stroke
				(width 0.1)
				(type default)
			)
			(layer "B.Fab")
		)
		(fp_line
			(start -0.67945 -0.3048)
			(end -0.67945 0.3048)
			(stroke
				(width 0.1)
				(type default)
			)
			(layer "B.Fab")
		)
		(fp_line
			(start -0.12065 -0.3048)
			(end -0.67945 -0.3048)
			(stroke
				(width 0.1)
				(type default)
			)
			(layer "B.Fab")
		)
		(fp_line
			(start 0.12065 -0.305054)
			(end 0.12065 -0.2794)
			(stroke
				(width 0.1)
				(type default)
			)
			(layer "B.Fab")
		)
		(fp_line
			(start 0.67945 -0.305054)
			(end 0.12065 -0.305054)
			(stroke
				(width 0.1)
				(type default)
			)
			(layer "B.Fab")
		)
		(pad "1" smd circle
			(at 0.40005 0 90)
			(size 0 0)
			(layers "B.Cu" "B.Mask" "B.Paste")
			(net "PVDDCR_CPU1_P0_PVCC")
		)
		(pad "2" smd circle
			(at -0.40005 0 90)
			(size 0 0)
			(layers "B.Cu" "B.Mask" "B.Paste")
			(net "PVDDIO_P0_VCC3")
		)
	)
	(footprint ""
		(layer "B.Cu")
		(at 117.388386 -253.432564)
		(property "Reference" "C2415"
			(at 0 0 0)
			(layer "B.SilkS")
			(hide yes)
			(effects
				(font
					(size 1.27 1.27)
				)
				(justify mirror)
			)
		)
		(property "Value" ""
			(at 0 0 0)
			(layer "B.Fab")
			(effects
				(font
					(size 1.27 1.27)
				)
				(justify mirror)
			)
		)
		(duplicate_pad_numbers_are_jumpers no)
		(fp_line
			(start -0.7874 -0.4064)
			(end -0.7874 0.4064)
			(stroke
				(width 0.1524)
				(type default)
			)
			(layer "B.SilkS")
		)
		(fp_line
			(start -0.7874 0.4064)
			(end 0.7874 0.4064)
			(stroke
				(width 0.1524)
				(type default)
			)
			(layer "B.SilkS")
		)
		(fp_line
			(start 0.7874 -0.4064)
			(end -0.7874 -0.4064)
			(stroke
				(width 0.1524)
				(type default)
			)
			(layer "B.SilkS")
		)
		(fp_line
			(start 0.7874 0.4064)
			(end 0.7874 -0.4064)
			(stroke
				(width 0.1524)
				(type default)
			)
			(layer "B.SilkS")
		)
		(fp_line
			(start -0.67945 -0.3048)
			(end -0.67945 0.3048)
			(stroke
				(width 0.1)
				(type default)
			)
			(layer "B.Fab")
		)
		(fp_line
			(start -0.67945 0.3048)
			(end -0.120396 0.3048)
			(stroke
				(width 0.1)
				(type default)
			)
			(layer "B.Fab")
		)
		(fp_line
			(start -0.12065 -0.3048)
			(end -0.67945 -0.3048)
			(stroke
				(width 0.1)
				(type default)
			)
			(layer "B.Fab")
		)
		(fp_line
			(start -0.12065 -0.2794)
			(end -0.12065 -0.3048)
			(stroke
				(width 0.1)
				(type default)
			)
			(layer "B.Fab")
		)
		(fp_line
			(start -0.120396 0.2794)
			(end 0.12065 0.2794)
			(stroke
				(width 0.1)
				(type default)
			)
			(layer "B.Fab")
		)
		(fp_line
			(start -0.120396 0.3048)
			(end -0.120396 0.2794)
			(stroke
				(width 0.1)
				(type default)
			)
			(layer "B.Fab")
		)
		(fp_line
			(start 0.12065 -0.305054)
			(end 0.12065 -0.2794)
			(stroke
				(width 0.1)
				(type default)
			)
			(layer "B.Fab")
		)
		(fp_line
			(start 0.12065 -0.2794)
			(end -0.12065 -0.2794)
			(stroke
				(width 0.1)
				(type default)
			)
			(layer "B.Fab")
		)
		(fp_line
			(start 0.12065 0.2794)
			(end 0.12065 0.3048)
			(stroke
				(width 0.1)
				(type default)
			)
			(layer "B.Fab")
		)
		(fp_line
			(start 0.12065 0.3048)
			(end 0.67945 0.3048)
			(stroke
				(width 0.1)
				(type default)
			)
			(layer "B.Fab")
		)
		(fp_line
			(start 0.67945 -0.305054)
			(end 0.12065 -0.305054)
			(stroke
				(width 0.1)
				(type default)
			)
			(layer "B.Fab")
		)
		(fp_line
			(start 0.67945 0.3048)
			(end 0.67945 -0.305054)
			(stroke
				(width 0.1)
				(type default)
			)
			(layer "B.Fab")
		)
		(pad "1" smd circle
			(at 0.40005 0 180)
			(size 0 0)
			(layers "B.Cu" "B.Mask" "B.Paste")
			(net "PVDDCR_SOC_P1")
		)
		(pad "2" smd circle
			(at -0.40005 0 180)
			(size 0 0)
			(layers "B.Cu" "B.Mask" "B.Paste")
			(net "GND")
		)
	)
	(footprint ""
		(layer "B.Cu")
		(at 450.482716 -10.594086 90)
		(property "Reference" "R8422"
			(at 0 0 90)
			(layer "B.SilkS")
			(hide yes)
			(effects
				(font
					(size 1.27 1.27)
				)
				(justify mirror)
			)
		)
		(property "Value" ""
			(at 0 0 90)
			(layer "B.Fab")
			(effects
				(font
					(size 1.27 1.27)
				)
				(justify mirror)
			)
		)
		(duplicate_pad_numbers_are_jumpers no)
		(fp_line
			(start 0.7874 -0.4064)
			(end -0.7874 -0.4064)
			(stroke
				(width 0.1524)
				(type default)
			)
			(layer "B.SilkS")
		)
		(fp_line
			(start -0.7874 -0.4064)
			(end -0.7874 0.4064)
			(stroke
				(width 0.1524)
				(type default)
			)
			(layer "B.SilkS")
		)
		(fp_line
			(start 0.7874 0.4064)
			(end 0.7874 -0.4064)
			(stroke
				(width 0.1524)
				(type default)
			)
			(layer "B.SilkS")
		)
		(fp_line
			(start -0.7874 0.4064)
			(end 0.7874 0.4064)
			(stroke
				(width 0.1524)
				(type default)
			)
			(layer "B.SilkS")
		)
		(fp_line
			(start 0.67945 -0.305054)
			(end 0.12065 -0.305054)
			(stroke
				(width 0.1)
				(type default)
			)
			(layer "B.Fab")
		)
		(fp_line
			(start 0.12065 -0.305054)
			(end 0.12065 -0.2794)
			(stroke
				(width 0.1)
				(type default)
			)
			(layer "B.Fab")
		)
		(fp_line
			(start -0.12065 -0.3048)
			(end -0.67945 -0.3048)
			(stroke
				(width 0.1)
				(type default)
			)
			(layer "B.Fab")
		)
		(fp_line
			(start -0.67945 -0.3048)
			(end -0.67945 0.3048)
			(stroke
				(width 0.1)
				(type default)
			)
			(layer "B.Fab")
		)
		(fp_line
			(start 0.12065 -0.2794)
			(end -0.12065 -0.2794)
			(stroke
				(width 0.1)
				(type default)
			)
			(layer "B.Fab")
		)
		(fp_line
			(start -0.12065 -0.2794)
			(end -0.12065 -0.3048)
			(stroke
				(width 0.1)
				(type default)
			)
			(layer "B.Fab")
		)
		(fp_line
			(start 0.12065 0.2794)
			(end 0.12065 0.3048)
			(stroke
				(width 0.1)
				(type default)
			)
			(layer "B.Fab")
		)
		(fp_line
			(start -0.120396 0.2794)
			(end 0.12065 0.2794)
			(stroke
				(width 0.1)
				(type default)
			)
			(layer "B.Fab")
		)
		(fp_line
			(start 0.67945 0.3048)
			(end 0.67945 -0.305054)
			(stroke
				(width 0.1)
				(type default)
			)
			(layer "B.Fab")
		)
		(fp_line
			(start 0.12065 0.3048)
			(end 0.67945 0.3048)
			(stroke
				(width 0.1)
				(type default)
			)
			(layer "B.Fab")
		)
		(fp_line
			(start -0.120396 0.3048)
			(end -0.120396 0.2794)
			(stroke
				(width 0.1)
				(type default)
			)
			(layer "B.Fab")
		)
		(fp_line
			(start -0.67945 0.3048)
			(end -0.120396 0.3048)
			(stroke
				(width 0.1)
				(type default)
			)
			(layer "B.Fab")
		)
		(pad "1" smd circle
			(at 0.40005 0 270)
			(size 0 0)
			(layers "B.Cu" "B.Mask" "B.Paste")
			(net "SGPIO_OCP_SFF_DATAOUT")
		)
		(pad "2" smd circle
			(at -0.40005 0 270)
			(size 0 0)
			(layers "B.Cu" "B.Mask" "B.Paste")
			(net "GND")
		)
	)
	(footprint ""
		(layer "B.Cu")
		(at 107.790742 -331.309472 -90)
		(property "Reference" "PC148_6"
			(at 0 0 90)
			(layer "B.SilkS")
			(hide yes)
			(effects
				(font
					(size 1.27 1.27)
				)
				(justify mirror)
			)
		)
		(property "Value" ""
			(at 0 0 90)
			(layer "B.Fab")
			(effects
				(font
					(size 1.27 1.27)
				)
				(justify mirror)
			)
		)
		(duplicate_pad_numbers_are_jumpers no)
		(fp_line
			(start -1.524 0.762)
			(end 1.524 0.762)
			(stroke
				(width 0.1524)
				(type default)
			)
			(layer "B.SilkS")
		)
		(fp_line
			(start 1.524 0.762)
			(end 1.524 -0.762)
			(stroke
				(width 0.1524)
				(type default)
			)
			(layer "B.SilkS")
		)
		(fp_line
			(start -1.524 -0.762)
			(end -1.524 0.762)
			(stroke
				(width 0.1524)
				(type default)
			)
			(layer "B.SilkS")
		)
		(fp_line
			(start 1.524 -0.762)
			(end -1.524 -0.762)
			(stroke
				(width 0.1524)
				(type default)
			)
			(layer "B.SilkS")
		)
		(fp_line
			(start -1.1049 0.724916)
			(end -1.1049 -0.724916)
			(stroke
				(width 0.1)
				(type default)
			)
			(layer "B.Fab")
		)
		(fp_line
			(start 1.1049 0.724916)
			(end -1.1049 0.724916)
			(stroke
				(width 0.1)
				(type default)
			)
			(layer "B.Fab")
		)
		(fp_line
			(start -1.1049 -0.724916)
			(end 1.1049 -0.724916)
			(stroke
				(width 0.1)
				(type default)
			)
			(layer "B.Fab")
		)
		(fp_line
			(start 1.1049 -0.724916)
			(end 1.1049 0.724916)
			(stroke
				(width 0.1)
				(type default)
			)
			(layer "B.Fab")
		)
		(pad "1" smd rect
			(at 0.889 0 270)
			(size 1.016 1.27)
			(layers "B.Cu" "B.Mask" "B.Paste")
			(net "PVDDCR_CPU1_P1")
		)
		(pad "2" smd rect
			(at -0.889 0 270)
			(size 1.016 1.27)
			(layers "B.Cu" "B.Mask" "B.Paste")
			(net "GND")
		)
	)
	(footprint ""
		(layer "B.Cu")
		(at 290.092384 -425.179998 180)
		(property "Reference" "R3111"
			(at 0 0 0)
			(layer "B.SilkS")
			(hide yes)
			(effects
				(font
					(size 1.27 1.27)
				)
				(justify mirror)
			)
		)
		(property "Value" ""
			(at 0 0 0)
			(layer "B.Fab")
			(effects
				(font
					(size 1.27 1.27)
				)
				(justify mirror)
			)
		)
		(duplicate_pad_numbers_are_jumpers no)
		(fp_line
			(start 0.7874 0.4064)
			(end 0.7874 -0.4064)
			(stroke
				(width 0.1524)
				(type default)
			)
			(layer "B.SilkS")
		)
		(fp_line
			(start 0.7874 -0.4064)
			(end -0.7874 -0.4064)
			(stroke
				(width 0.1524)
				(type default)
			)
			(layer "B.SilkS")
		)
		(fp_line
			(start -0.7874 0.4064)
			(end 0.7874 0.4064)
			(stroke
				(width 0.1524)
				(type default)
			)
			(layer "B.SilkS")
		)
		(fp_line
			(start -0.7874 -0.4064)
			(end -0.7874 0.4064)
			(stroke
				(width 0.1524)
				(type default)
			)
			(layer "B.SilkS")
		)
		(fp_line
			(start 0.67945 0.3048)
			(end 0.67945 -0.305054)
			(stroke
				(width 0.1)
				(type default)
			)
			(layer "B.Fab")
		)
		(fp_line
			(start 0.67945 -0.305054)
			(end 0.12065 -0.305054)
			(stroke
				(width 0.1)
				(type default)
			)
			(layer "B.Fab")
		)
		(fp_line
			(start 0.12065 0.3048)
			(end 0.67945 0.3048)
			(stroke
				(width 0.1)
				(type default)
			)
			(layer "B.Fab")
		)
		(fp_line
			(start 0.12065 0.2794)
			(end 0.12065 0.3048)
			(stroke
				(width 0.1)
				(type default)
			)
			(layer "B.Fab")
		)
		(fp_line
			(start 0.12065 -0.2794)
			(end -0.12065 -0.2794)
			(stroke
				(width 0.1)
				(type default)
			)
			(layer "B.Fab")
		)
		(fp_line
			(start 0.12065 -0.305054)
			(end 0.12065 -0.2794)
			(stroke
				(width 0.1)
				(type default)
			)
			(layer "B.Fab")
		)
		(fp_line
			(start -0.120396 0.3048)
			(end -0.120396 0.2794)
			(stroke
				(width 0.1)
				(type default)
			)
			(layer "B.Fab")
		)
		(fp_line
			(start -0.120396 0.2794)
			(end 0.12065 0.2794)
			(stroke
				(width 0.1)
				(type default)
			)
			(layer "B.Fab")
		)
		(fp_line
			(start -0.12065 -0.2794)
			(end -0.12065 -0.3048)
			(stroke
				(width 0.1)
				(type default)
			)
			(layer "B.Fab")
		)
		(fp_line
			(start -0.12065 -0.3048)
			(end -0.67945 -0.3048)
			(stroke
				(width 0.1)
				(type default)
			)
			(layer "B.Fab")
		)
		(fp_line
			(start -0.67945 0.3048)
			(end -0.120396 0.3048)
			(stroke
				(width 0.1)
				(type default)
			)
			(layer "B.Fab")
		)
		(fp_line
			(start -0.67945 -0.3048)
			(end -0.67945 0.3048)
			(stroke
				(width 0.1)
				(type default)
			)
			(layer "B.Fab")
		)
		(pad "1" smd circle
			(at 0.40005 0)
			(size 0 0)
			(layers "B.Cu" "B.Mask" "B.Paste")
			(net "I3C_BMC_SWB_SDA")
		)
		(pad "2" smd circle
			(at -0.40005 0)
			(size 0 0)
			(layers "B.Cu" "B.Mask" "B.Paste")
			(net "I3C_BMC_SWB_R_SDA")
		)
	)
	(footprint ""
		(layer "B.Cu")
		(at 139.516358 -393.242546 180)
		(property "Reference" "R858"
			(at 0 0 0)
			(layer "B.SilkS")
			(hide yes)
			(effects
				(font
					(size 1.27 1.27)
				)
				(justify mirror)
			)
		)
		(property "Value" ""
			(at 0 0 0)
			(layer "B.Fab")
			(effects
				(font
					(size 1.27 1.27)
				)
				(justify mirror)
			)
		)
		(duplicate_pad_numbers_are_jumpers no)
		(fp_line
			(start 1.2954 0.5842)
			(end 1.2954 -0.5842)
			(stroke
				(width 0.1524)
				(type default)
			)
			(layer "B.SilkS")
		)
		(fp_line
			(start 1.2954 -0.5842)
			(end -1.2954 -0.5842)
			(stroke
				(width 0.1524)
				(type default)
			)
			(layer "B.SilkS")
		)
		(fp_line
			(start -1.2954 0.5842)
			(end 1.2954 0.5842)
			(stroke
				(width 0.1524)
				(type default)
			)
			(layer "B.SilkS")
		)
		(fp_line
			(start -1.2954 -0.5842)
			(end -1.2954 0.5842)
			(stroke
				(width 0.1524)
				(type default)
			)
			(layer "B.SilkS")
		)
		(fp_line
			(start 1.1938 0.4064)
			(end 1.1938 -0.406654)
			(stroke
				(width 0.1)
				(type default)
			)
			(layer "B.Fab")
		)
		(fp_line
			(start 1.1938 -0.406654)
			(end 0.8636 -0.406654)
			(stroke
				(width 0.1)
				(type default)
			)
			(layer "B.Fab")
		)
		(fp_line
			(start 0.8636 0.4572)
			(end 0.8636 0.4318)
			(stroke
				(width 0.1)
				(type default)
			)
			(layer "B.Fab")
		)
		(fp_line
			(start 0.8636 0.4318)
			(end 0.8636 0.4064)
			(stroke
				(width 0.1)
				(type default)
			)
			(layer "B.Fab")
		)
		(fp_line
			(start 0.8636 0.4064)
			(end 1.1938 0.4064)
			(stroke
				(width 0.1)
				(type default)
			)
			(layer "B.Fab")
		)
		(fp_line
			(start 0.8636 -0.406654)
			(end 0.8636 -0.4572)
			(stroke
				(width 0.1)
				(type default)
			)
			(layer "B.Fab")
		)
		(fp_line
			(start 0.8636 -0.4572)
			(end -0.8636 -0.4572)
			(stroke
				(width 0.1)
				(type default)
			)
			(layer "B.Fab")
		)
		(fp_line
			(start -0.8636 0.4572)
			(end 0.8636 0.4572)
			(stroke
				(width 0.1)
				(type default)
			)
			(layer "B.Fab")
		)
		(fp_line
			(start -0.8636 0.4064)
			(end -0.8636 0.4572)
			(stroke
				(width 0.1)
				(type default)
			)
			(layer "B.Fab")
		)
		(fp_line
			(start -0.8636 -0.406654)
			(end -1.1938 -0.406654)
			(stroke
				(width 0.1)
				(type default)
			)
			(layer "B.Fab")
		)
		(fp_line
			(start -0.8636 -0.4572)
			(end -0.8636 -0.406654)
			(stroke
				(width 0.1)
				(type default)
			)
			(layer "B.Fab")
		)
		(fp_line
			(start -1.1938 0.4064)
			(end -0.8636 0.4064)
			(stroke
				(width 0.1)
				(type default)
			)
			(layer "B.Fab")
		)
		(fp_line
			(start -1.1938 -0.406654)
			(end -1.1938 0.4064)
			(stroke
				(width 0.1)
				(type default)
			)
			(layer "B.Fab")
		)
		(pad "1" smd rect
			(at 0.7366 0 90)
			(size 0.7112 0.8128)
			(layers "B.Cu" "B.Mask" "B.Paste")
			(net "P0V9_CPU1_RT_2D")
		)
		(pad "2" smd rect
			(at -0.7366 0 90)
			(size 0.7112 0.8128)
			(layers "B.Cu" "B.Mask" "B.Paste")
			(net "P0V9_CPU1_RT2_2A_2D")
		)
	)
	(footprint ""
		(layer "B.Cu")
		(at 321.530726 -416.899344 90)
		(property "Reference" "C6543"
			(at 0 0 90)
			(layer "B.SilkS")
			(hide yes)
			(effects
				(font
					(size 1.27 1.27)
				)
				(justify mirror)
			)
		)
		(property "Value" ""
			(at 0 0 90)
			(layer "B.Fab")
			(effects
				(font
					(size 1.27 1.27)
				)
				(justify mirror)
			)
		)
		(duplicate_pad_numbers_are_jumpers no)
		(fp_line
			(start 0.299974 -0.150114)
			(end -0.299974 -0.150114)
			(stroke
				(width 0.1)
				(type default)
			)
			(layer "B.Fab")
		)
		(fp_line
			(start -0.299974 -0.150114)
			(end -0.299974 0.150114)
			(stroke
				(width 0.1)
				(type default)
			)
			(layer "B.Fab")
		)
		(fp_line
			(start 0.299974 0.150114)
			(end 0.299974 -0.150114)
			(stroke
				(width 0.1)
				(type default)
			)
			(layer "B.Fab")
		)
		(fp_line
			(start -0.299974 0.150114)
			(end 0.299974 0.150114)
			(stroke
				(width 0.1)
				(type default)
			)
			(layer "B.Fab")
		)
		(pad "1" smd rect
			(at 0.2667 0 270)
			(size 0.3048 0.381)
			(layers "B.Cu" "B.Mask" "B.Paste")
			(net "P5E_CPU0_P1_TX_BUF_C_DP<5>")
		)
		(pad "2" smd rect
			(at -0.2667 0 270)
			(size 0.3048 0.381)
			(layers "B.Cu" "B.Mask" "B.Paste")
			(net "P5E_CPU0_P1_TX_BUF_DP<5>")
		)
	)
)
